# T6G (Grand Teton) — schematic parts with pin connectivity, parts 519–688 of 8303; source: Cadence DE-HDL packaged netlist (pstxprt.dat, pstxnet.dat, pstchip.dat)

C518  Q_CAP  10UF 25V 10% X6S  pkg C0805  page 103 : 1 = P12V_MEM_CPU1 ; 2 = GND
C519  Q_CAP  0.1UF 10V 10% X7S  pkg C0201  page 279 : 1 = P1V8_CPU0_RT0_1A ; 2 = GND
C520  Q_CAP  0.1UF 10V 10% X7S  pkg C0201  page 279 : 1 = P1V8_CPU0_RT0_1A ; 2 = GND
C521  Q_CAP  1UF 4V 20% X6S  pkg 0201  page 279 : 1 = P0V9_CPU0_RT0_2A ; 2 = GND
C522  Q_CAP  0.1UF 10V 10% X7S  pkg C0201  page 279 : 1 = P0V9_CPU0_RT_2D ; 2 = GND
C523  Q_CAP  0.1UF 10V 10% X7S  pkg C0201  page 279 : 1 = P0V9_CPU0_RT0_2A ; 2 = GND
C524  Q_CAP  0.1UF 10V 10% X7S  pkg C0201  page 279 : 1 = P0V9_CPU0_RT_2D ; 2 = GND
C525  Q_CAP  1UF 4V 20% X6S  pkg 0201  page 279 : 1 = P0V9_CPU0_RT0_2A ; 2 = GND
C526  Q_CAP  1UF 4V 20% X6S  pkg 0201  page 279 : 1 = P0V9_CPU0_RT0_2A ; 2 = GND
C527  Q_CAP  10UF 25V 10% X6S  pkg C0805  page 103 : 1 = P12V_MEM_CPU1 ; 2 = GND
C528  Q_CAP  1UF 4V 20% X6S  pkg 0201  page 279 : 1 = P0V9_CPU0_RT_2D ; 2 = GND
C529  Q_CAP  1UF 4V 20% X6S  pkg 0201  page 279 : 1 = P0V9_CPU0_RT0_2A ; 2 = GND
C530  Q_CAP  10UF 25V 10% X6S  pkg C0805  page 104 : 1 = P12V_MEM_CPU1 ; 2 = GND
C531  Q_CAP  10UF 25V 10% X6S  pkg C0805  page 104 : 1 = P12V_MEM_CPU1 ; 2 = GND
C532  Q_CAP  10UF 25V 10% X6S  pkg C0805  page 105 : 1 = P12V_MEM_CPU1 ; 2 = GND
C533  Q_CAP  10UF 25V 10% X6S  pkg C0805  page 105 : 1 = P12V_MEM_CPU1 ; 2 = GND
C534  Q_CAP  10UF 25V 10% X6S  pkg C0805  page 106 : 1 = P12V_MEM_CPU1 ; 2 = GND
C535  Q_CAP  10UF 25V 10% X6S  pkg C0805  page 106 : 1 = P12V_MEM_CPU1 ; 2 = GND
C536  Q_CAP  10UF 25V 10% X6S  pkg C0805  page 107 : 1 = P12V_MEM_CPU1 ; 2 = GND
C537  Q_CAP  10UF 25V 10% X6S  pkg C0805  page 107 : 1 = P12V_MEM_CPU1 ; 2 = GND
C538  Q_CAP  0.1UF 10V 10% X7S  pkg C0201  page 279 : 1 = P0V9_CPU0_RT0_2A_2D ; 2 = GND
C539  Q_CAP  1UF 4V 20% X6S  pkg 0201  page 279 : 1 = P0V9_CPU0_RT0_2A ; 2 = GND
C540  Q_CAP  0.1UF 10V 10% X7S  pkg C0201  page 279 : 1 = P0V9_CPU0_RT_2D ; 2 = GND
C541  Q_CAP  0.1UF 10V 10% X7S  pkg C0201  page 279 : 1 = P0V9_CPU0_RT0_2A ; 2 = GND
C542  Q_CAP  1UF 4V 20% X6S  pkg 0201  page 279 : 1 = P0V9_CPU0_RT0_2A_2D ; 2 = GND
C543  Q_CAP  0.1UF 10V 10% X7S  pkg C0201  page 279 : 1 = P0V9_CPU0_RT0_2A ; 2 = GND
C544  Q_CAP  0.1UF 10V 10% X7S  pkg C0201  page 279 : 1 = P0V9_CPU0_RT0_2A_2D ; 2 = GND
C545  Q_CAP  1UF 4V 20% X6S  pkg 0201  page 279 : 1 = P0V9_CPU0_RT0_2A_2D ; 2 = GND
C546  Q_CAP  10UF 25V 10% X6S  pkg C0805  page 108 : 1 = P12V_MEM_CPU1 ; 2 = GND
C547  Q_CAP  10UF 25V 10% X6S  pkg C0805  page 108 : 1 = P12V_MEM_CPU1 ; 2 = GND
C548  Q_CAP  10UF 25V 10% X6S  pkg C0805  page 109 : 1 = P12V_MEM_CPU1 ; 2 = GND
C549  Q_CAP  10UF 25V 10% X6S  pkg C0805  page 109 : 1 = P12V_MEM_CPU1 ; 2 = GND
C550  Q_CAP  100UF 4V 20% X6S  pkg C0805  page 279 : 1 = P0V9_CPU0_RT0_2A ; 2 = GND
C551  Q_CAP  0.01UF 50V 10% X7R  pkg C0402  page 172 : 1 = CPU0_HDT_CONN_TESTEN ; 2 = GND
C552  Q_CAP  0.1UF 25V 10% X7R  pkg 0402  page 84 : 1 = P1V8_AUX ; 2 = GND
C553  Q_CAP  0.1UF 25V 10% X7R  pkg 0402  page 171 : 1 = P3V3_AUX ; 2 = GND
C554  Q_CAP  4.7UF 6.3V 20% X6S  pkg 0402  page 279 : 1 = P0V9_CPU0_RT0_2A ; 2 = GND
C555  Q_CAP  1UF 4V 20% X6S  pkg 0201  page 279 : 1 = P0V9_CPU0_RT0_2A ; 2 = GND
C556  Q_CAP  100UF 4V 20% X6S  pkg C0805  page 279 : 1 = P0V9_CPU0_RT0_2A ; 2 = GND
C557  Q_CAP  4.7UF 6.3V 20% X6S  pkg 0402  page 279 : 1 = P0V9_CPU0_RT0_2A ; 2 = GND
C558  Q_CAP  0.1UF 10V 10% X7S  pkg C0201  page 279 : 1 = P0V9_CPU0_RT0_2A ; 2 = GND
C559  Q_CAP  100UF 4V 20% X6S  pkg C0805  page 279 : 1 = P0V9_CPU0_RT_2D ; 2 = GND
C560  Q_CAP  100UF 4V 20% X6S  pkg C0805  page 279 : 1 = P0V9_CPU0_RT0_2A ; 2 = GND
C561  Q_CAP  10UF 6.3V 20% X6S  pkg C0402  page 279 : 1 = P0V9_CPU0_RT0_2A ; 2 = GND
C562  Q_CAP  1UF 4V 20% X6S  pkg 0201  page 279 : 1 = P0V9_CPU0_RT0_2A ; 2 = GND
C563  Q_CAP  22UF 4V 20% X6S  pkg C0402  page 279 : 1 = P0V9_CPU0_RT_2D ; 2 = GND
C564  Q_CAP  100UF 4V 20% X6S  pkg C0805  page 279 : 1 = P0V9_CPU0_RT0_2A ; 2 = GND
C565  Q_CAP  22UF 4V 20% X6S  pkg C0402  page 279 : 1 = P0V9_CPU0_RT0_2A ; 2 = GND
C566  Q_CAP  0.1UF 10V 10% X7S  pkg C0201  page 279 : 1 = P0V9_CPU0_RT0_2A ; 2 = GND
C567  Q_CAP  10UF 6.3V 20% X6S  pkg C0402  page 279 : 1 = P0V9_CPU0_RT0_2A ; 2 = GND
C568  Q_CAP  22UF 4V 20% X6S  pkg C0402  page 279 : 1 = P0V9_CPU0_RT0_2A ; 2 = GND
C569  Q_CAP  4.7UF 6.3V 20% X6S  pkg 0402  page 279 : 1 = P0V9_CPU0_RT_2D ; 2 = GND
C570  Q_CAP  1UF 4V 20% X6S  pkg 0201  page 279 : 1 = P0V9_CPU0_RT0_2A ; 2 = GND
C571  Q_CAP  4.7UF 6.3V 20% X6S  pkg 0402  page 279 : 1 = P0V9_CPU0_RT0_2A ; 2 = GND
C572  Q_CAP  4.7UF 6.3V 20% X6S  pkg 0402  page 279 : 1 = P0V9_CPU0_RT0_2A ; 2 = GND
C573  Q_CAP  1UF 4V 20% X6S  pkg 0201  page 279 : 1 = P0V9_CPU0_RT0_2A ; 2 = GND
C574  Q_CAP  10UF 6.3V 20% X6S  pkg C0402  page 279 : 1 = P0V9_CPU0_RT_2D ; 2 = GND
C575  Q_CAP  22UF 4V 20% X6S  pkg C0402  page 279 : 1 = P0V9_CPU0_RT0_2A ; 2 = GND
C576  Q_CAP  0.1UF 10V 10% X7S  pkg C0201  page 279 : 1 = P0V9_CPU0_RT0_2A ; 2 = GND
C577  Q_CAP  1UF 4V 20% X6S  pkg 0201  page 279 : 1 = P0V9_CPU0_RT0_2A ; 2 = GND
C578  Q_CAP  0.1UF 10V 10% X7S  pkg C0201  page 279 : 1 = P0V9_CPU0_RT_2D ; 2 = GND
C579  Q_CAP  10UF 6.3V 20% X6S  pkg C0402  page 279 : 1 = P0V9_CPU0_RT0_2A ; 2 = GND
C580  Q_CAP  0.1UF 10V 10% X7S  pkg C0201  page 279 : 1 = P0V9_CPU0_RT0_2A ; 2 = GND
C581  Q_CAP  1UF 4V 20% X6S  pkg 0201  page 279 : 1 = P0V9_CPU0_RT0_2A ; 2 = GND
C582  Q_CAP  0.1UF 10V 10% X7S  pkg C0201  page 279 : 1 = P0V9_CPU0_RT0_2A ; 2 = GND
C583  Q_CAP  0.1UF 10V 10% X7S  pkg C0201  page 279 : 1 = P0V9_CPU0_RT0_2A ; 2 = GND
C584  Q_CAP  10UF 6.3V 20% X6S  pkg C0402  page 279 : 1 = P0V9_CPU0_RT0_2A ; 2 = GND
C585  Q_CAP  0.1UF 10V 10% X7S  pkg C0201  page 279 : 1 = P0V9_CPU0_RT0_2A ; 2 = GND
C586  Q_CAP  22UF 4V 20% X6S  pkg C0402  page 279 : 1 = P0V9_CPU0_RT0_2A ; 2 = GND
C587  Q_CAP  100UF 4V 20% X6S  pkg C0805  page 290 : 1 = P1V8_CPU0_RT_1D ; 2 = GND
C588  Q_CAP  100UF 4V 20% X6S  pkg C0805  page 290 : 1 = P1V8_CPU0_RT1_1A ; 2 = GND
C589  Q_CAP  22UF 4V 20% X6S  pkg C0402  page 290 : 1 = P1V8_CPU0_RT_1D ; 2 = GND
C590  Q_CAP  22UF 4V 20% X6S  pkg C0402  page 290 : 1 = P1V8_CPU0_RT1_1A ; 2 = GND
C591  Q_CAP  10UF 6.3V 20% X6S  pkg C0402  page 290 : 1 = P1V8_CPU0_RT_1D ; 2 = GND
C592  Q_CAP  0.1UF 25V 10% X7R  pkg 0402  page 134 : 1 = P3V3_AUX ; 2 = GND
C593  Q_CAP  0.1UF 25V 10% X7R  pkg 0402  page 134 : 1 = P3V3_AUX ; 2 = GND
C594  Q_CAP  4.7UF 6.3V 20% X6S  pkg 0402  page 290 : 1 = P1V8_CPU0_RT1_1A ; 2 = GND
C595  Q_CAP  10UF 6.3V 20% X6S  pkg C0402  page 290 : 1 = P1V8_CPU0_RT1_1A ; 2 = GND
C596  Q_CAP  4.7UF 6.3V 20% X6S  pkg 0402  page 290 : 1 = P1V8_CPU0_RT_1D ; 2 = GND
C597  Q_CAP  1UF 4V 20% X6S  pkg 0201  page 290 : 1 = P1V8_CPU0_RT1_1A ; 2 = GND
C598  Q_CAP  1UF 4V 20% X6S  pkg 0201  page 290 : 1 = P1V8_CPU0_RT1_1A_1D ; 2 = GND
C599  Q_CAP  1UF 4V 20% X6S  pkg 0201  page 290 : 1 = P1V8_CPU0_RT1_1A ; 2 = GND
C600  Q_CAP  0.1UF 10V 10% X7S  pkg C0201  page 290 : 1 = P1V8_CPU0_RT1_1A ; 2 = GND
C601  Q_CAP  0.1UF 10V 10% X7S  pkg C0201  page 290 : 1 = P1V8_CPU0_RT1_1A_1D ; 2 = GND
C602  Q_CAP  0.1UF 10V 10% X7S  pkg C0201  page 290 : 1 = P1V8_CPU0_RT1_1A ; 2 = GND
C603  Q_CAP  0.1UF 10V 10% X7S  pkg C0201  page 290 : 1 = P1V8_CPU0_RT1_1A ; 2 = GND
C604  Q_CAP  0.001UF 50V 10% X7R  pkg C0402  page 172 : 1 = HDT_HDR_TCK ; 2 = GND
C605  Q_CAP  0.001UF 50V 10% X7R  pkg C0402  page 172 : 1 = HDT_HDR_TDI ; 2 = GND
C606  Q_CAP  0.1UF 10V 10% X7S  pkg C0201  page 290 : 1 = P1V8_CPU0_RT1_1A ; 2 = GND
C607  Q_CAP  1UF 4V 20% X6S  pkg 0201  page 290 : 1 = P0V9_CPU0_RT1_2A ; 2 = GND
C608  Q_CAP  0.1UF 10V 10% X7S  pkg C0201  page 290 : 1 = P0V9_CPU0_RT_2D ; 2 = GND
C609  Q_CAP  1UF 4V 20% X6S  pkg 0201  page 290 : 1 = P0V9_CPU0_RT1_2A ; 2 = GND
C610  Q_CAP  0.1UF 10V 10% X7S  pkg C0201  page 290 : 1 = P0V9_CPU0_RT_2D ; 2 = GND
C611  Q_CAP  0.1UF 25V 10% X7R  pkg 0402  page 160 : 1 = P3V3_AUX ; 2 = GND
C612  Q_CAP  0.1UF 25V 10% X7R  pkg 0402  page 160 : 1 = PVDD18_S5_P0 ; 2 = GND
C613  Q_CAP  1UF 4V 20% X6S  pkg 0201  page 290 : 1 = P0V9_CPU0_RT1_2A ; 2 = GND
C614  Q_CAP  0.1UF 10V 10% X7S  pkg C0201  page 290 : 1 = P0V9_CPU0_RT1_2A ; 2 = GND
C615  Q_CAP  0.1UF 10V 10% X7S  pkg C0201  page 290 : 1 = P0V9_CPU0_RT_2D ; 2 = GND
C616  Q_CAP  0.1UF 10V 10% X7S  pkg C0201  page 290 : 1 = P0V9_CPU0_RT1_2A ; 2 = GND
C617  Q_CAP  0.1UF 10V 10% X7S  pkg C0201  page 290 : 1 = P0V9_CPU0_RT1_2A_2D ; 2 = GND
C618  Q_CAP  1UF 4V 20% X6S  pkg 0201  page 290 : 1 = P0V9_CPU0_RT1_2A ; 2 = GND
C619  Q_CAP  0.1UF 10V 10% X7S  pkg C0201  page 290 : 1 = P0V9_CPU0_RT_2D ; 2 = GND
C620  Q_CAP  1UF 4V 20% X6S  pkg 0201  page 290 : 1 = P0V9_CPU0_RT1_2A ; 2 = GND
C621  Q_CAP  1UF 4V 20% X6S  pkg 0201  page 290 : 1 = P0V9_CPU0_RT1_2A_2D ; 2 = GND
C622  Q_CAP  1UF 4V 20% X6S  pkg 0201  page 290 : 1 = P0V9_CPU0_RT1_2A ; 2 = GND
C623  Q_CAP  0.1UF 10V 10% X7S  pkg C0201  page 290 : 1 = P0V9_CPU0_RT1_2A_2D ; 2 = GND
C624  Q_CAP  1UF 4V 20% X6S  pkg 0201  page 290 : 1 = P0V9_CPU0_RT1_2A_2D ; 2 = GND
C625  Q_CAP  100UF 4V 20% X6S  pkg C0805  page 290 : 1 = P0V9_CPU0_RT1_2A ; 2 = GND
C626  Q_CAP  10UF 6.3V 20% X6S  pkg C0402  page 290 : 1 = P0V9_CPU0_RT1_2A ; 2 = GND
C627  Q_CAP  0.1UF 10V 10% X7S  pkg C0201  page 290 : 1 = P0V9_CPU0_RT1_2A ; 2 = GND
C628  Q_CAP  100UF 4V 20% X6S  pkg C0805  page 290 : 1 = P0V9_CPU0_RT1_2A ; 2 = GND
C629  Q_CAP  0.1UF 25V 10% X7R  pkg 0402  page 238 : 1 = P3V3_AUX ; 2 = GND
C630  Q_CAP  22UF 4V 20% X6S  pkg C0402  page 290 : 1 = P0V9_CPU0_RT1_2A ; 2 = GND
C631  Q_CAP  0.1UF 10V 10% X7S  pkg C0201  page 290 : 1 = P0V9_CPU0_RT1_2A ; 2 = GND
C632  Q_CAP  100UF 4V 20% X6S  pkg C0805  page 290 : 1 = P0V9_CPU0_RT_2D ; 2 = GND
C633  Q_CAP  100UF 4V 20% X6S  pkg C0805  page 290 : 1 = P0V9_CPU0_RT1_2A ; 2 = GND
C634  Q_CAP  22UF 4V 20% X6S  pkg C0402  page 290 : 1 = P0V9_CPU0_RT1_2A ; 2 = GND
C635  Q_CAP  0.1UF 10V 10% X7S  pkg C0201  page 290 : 1 = P0V9_CPU0_RT1_2A ; 2 = GND
C636  Q_CAP  22UF 4V 20% X6S  pkg C0402  page 290 : 1 = P0V9_CPU0_RT_2D ; 2 = GND
C637  Q_CAP  100UF 4V 20% X6S  pkg C0805  page 290 : 1 = P0V9_CPU0_RT1_2A ; 2 = GND
C638  Q_CAP  4.7UF 6.3V 20% X6S  pkg 0402  page 290 : 1 = P0V9_CPU0_RT1_2A ; 2 = GND
C639  Q_CAP  0.1UF 25V 10% X7R  pkg 0402  page 132 : 1 = P3V3_AUX ; 2 = GND
C640  Q_CAP  0.1UF 25V 10% X7R  pkg 0402  page 132 : 1 = P3V3_AUX ; 2 = GND
C641  Q_CAP  0.1UF 25V 10% X7R  pkg 0402  page 132 : 1 = P3V3_AUX ; 2 = GND
C642  Q_CAP  1000PF 50V 5% X7R  pkg 0402  page 224 : 1 = PVDD11_S3_P1_EN_R ; 2 = GND
C643  Q_CAP  1UF 4V 20% X6S  pkg 0201  page 290 : 1 = P0V9_CPU0_RT1_2A ; 2 = GND
C644  Q_CAP  4.7UF 6.3V 20% X6S  pkg 0402  page 290 : 1 = P0V9_CPU0_RT1_2A ; 2 = GND
C645  Q_CAP  10UF 6.3V 20% X6S  pkg C0402  page 290 : 1 = P0V9_CPU0_RT1_2A ; 2 = GND
C646  Q_CAP  10UF 6.3V 20% X6S  pkg C0402  page 290 : 1 = P0V9_CPU0_RT_2D ; 2 = GND
C647  Q_CAP  1UF 4V 20% X6S  pkg 0201  page 290 : 1 = P0V9_CPU0_RT1_2A ; 2 = GND
C648  Q_CAP  10UF 6.3V 20% X6S  pkg C0402  page 290 : 1 = P0V9_CPU0_RT1_2A ; 2 = GND
C649  Q_CAP  4.7UF 6.3V 20% X6S  pkg 0402  page 290 : 1 = P0V9_CPU0_RT1_2A ; 2 = GND
C650  Q_CAP  0.1UF 10V 10% X7S  pkg C0201  page 290 : 1 = P0V9_CPU0_RT1_2A ; 2 = GND
C651  Q_CAP  4.7UF 6.3V 20% X6S  pkg 0402  page 290 : 1 = P0V9_CPU0_RT_2D ; 2 = GND
C652  Q_CAP  4.7UF 6.3V 20% X6S  pkg 0402  page 290 : 1 = P0V9_CPU0_RT1_2A ; 2 = GND
C653  Q_CAP  1UF 4V 20% X6S  pkg 0201  page 290 : 1 = P0V9_CPU0_RT1_2A ; 2 = GND
C654  Q_CAP  1UF 4V 20% X6S  pkg 0201  page 290 : 1 = P0V9_CPU0_RT1_2A ; 2 = GND
C655  Q_CAP  1UF 4V 20% X6S  pkg 0201  page 290 : 1 = P0V9_CPU0_RT_2D ; 2 = GND
C656  Q_CAP  22UF 4V 20% X6S  pkg C0402  page 290 : 1 = P0V9_CPU0_RT1_2A ; 2 = GND
C657  Q_CAP  0.1UF 10V 10% X7S  pkg C0201  page 290 : 1 = P0V9_CPU0_RT1_2A ; 2 = GND
C658  Q_CAP  0.1UF 10V 10% X7S  pkg C0201  page 290 : 1 = P0V9_CPU0_RT1_2A ; 2 = GND
C659  Q_CAP  0.1UF 10V 10% X7S  pkg C0201  page 290 : 1 = P0V9_CPU0_RT1_2A ; 2 = GND
C660  Q_CAP  1UF 4V 20% X6S  pkg 0201  page 290 : 1 = P0V9_CPU0_RT1_2A ; 2 = GND
C661  Q_CAP  10UF 6.3V 20% X6S  pkg C0402  page 290 : 1 = P0V9_CPU0_RT1_2A ; 2 = GND
C662  Q_CAP  0.1UF 10V 10% X7S  pkg C0201  page 290 : 1 = P0V9_CPU0_RT1_2A ; 2 = GND
C663  Q_CAP  22UF 4V 20% X6S  pkg C0402  page 290 : 1 = P0V9_CPU0_RT1_2A ; 2 = GND
C664  Q_CAP  0.1UF 10V 10% X7S  pkg C0201  page 289 : 1 = P1V8_CPU0_RT_1D ; 2 = GND
C665  Q_CAP  100UF 4V 20% X6S  pkg C0805  page 301 : 1 = P1V8_CPU0_RT_1D ; 2 = GND
C666  Q_CAP  100UF 4V 20% X6S  pkg C0805  page 301 : 1 = P1V8_CPU0_RT2_1A ; 2 = GND
C667  Q_CAP  22UF 4V 20% X6S  pkg C0402  page 301 : 1 = P1V8_CPU0_RT_1D ; 2 = GND
C668  Q_CAP  22UF 4V 20% X6S  pkg C0402  page 301 : 1 = P1V8_CPU0_RT2_1A ; 2 = GND
C669  Q_CAP  10UF 6.3V 20% X6S  pkg C0402  page 301 : 1 = P1V8_CPU0_RT_1D ; 2 = GND
C670  Q_CAP  4.7UF 6.3V 20% X6S  pkg 0402  page 301 : 1 = P1V8_CPU0_RT2_1A ; 2 = GND
C671  Q_CAP  10UF 6.3V 20% X6S  pkg C0402  page 301 : 1 = P1V8_CPU0_RT2_1A ; 2 = GND
C672  Q_CAP  4.7UF 6.3V 20% X6S  pkg 0402  page 301 : 1 = P1V8_CPU0_RT_1D ; 2 = GND
C673  Q_CAP  1UF 4V 20% X6S  pkg 0201  page 301 : 1 = P1V8_CPU0_RT2_1A ; 2 = GND
C674  Q_CAP  0.1UF 25V 10% EMPTY  pkg 0402  page 209 : 1 = PVDD18_S5_P0_EN ; 2 = GND
C675  Q_CAP  0.1UF 25V 10% EMPTY  pkg 0402  page 226 : 1 = PVDD18_S5_P1_EN ; 2 = GND
C676  Q_CAP  1UF 4V 20% X6S  pkg 0201  page 301 : 1 = P1V8_CPU0_RT2_1A_1D ; 2 = GND
C677  Q_CAP  1UF 4V 20% X6S  pkg 0201  page 301 : 1 = P1V8_CPU0_RT2_1A ; 2 = GND
C678  Q_CAP_DIFFBUS  DIFF BUS_0.22UF 6.3V 20% X6S  pkg C0201  page 67 : 1 = P5E_CPU1_G1_TX_C_DN<15> ; 2 = P5E_CPU1_G1_TX_DN<15>
C679  Q_CAP_DIFFBUS  DIFF BUS_0.22UF 6.3V 20% X6S  pkg C0201  page 67 : 1 = P5E_CPU1_G1_TX_C_DP<15> ; 2 = P5E_CPU1_G1_TX_DP<15>
C680  Q_CAP_DIFFBUS  DIFF BUS_0.22UF 6.3V 20% X6S  pkg C0201  page 67 : 1 = P5E_CPU1_G1_TX_C_DN<14> ; 2 = P5E_CPU1_G1_TX_DN<14>
C681  Q_CAP_DIFFBUS  DIFF BUS_0.22UF 6.3V 20% X6S  pkg C0201  page 67 : 1 = P5E_CPU1_G1_TX_C_DP<14> ; 2 = P5E_CPU1_G1_TX_DP<14>
C682  Q_CAP_DIFFBUS  DIFF BUS_0.22UF 6.3V 20% X6S  pkg C0201  page 67 : 1 = P5E_CPU1_G1_TX_C_DN<13> ; 2 = P5E_CPU1_G1_TX_DN<13>
C683  Q_CAP_DIFFBUS  DIFF BUS_0.22UF 6.3V 20% X6S  pkg C0201  page 67 : 1 = P5E_CPU1_G1_TX_C_DP<13> ; 2 = P5E_CPU1_G1_TX_DP<13>
C684  Q_CAP_DIFFBUS  DIFF BUS_0.22UF 6.3V 20% X6S  pkg C0201  page 67 : 1 = P5E_CPU1_G1_TX_C_DN<12> ; 2 = P5E_CPU1_G1_TX_DN<12>
C685  Q_CAP_DIFFBUS  DIFF BUS_0.22UF 6.3V 20% X6S  pkg C0201  page 67 : 1 = P5E_CPU1_G1_TX_C_DP<12> ; 2 = P5E_CPU1_G1_TX_DP<12>
C686  Q_CAP_DIFFBUS  DIFF BUS_0.22UF 6.3V 20% X6S  pkg C0201  page 67 : 1 = P5E_CPU1_G1_TX_C_DN<11> ; 2 = P5E_CPU1_G1_TX_DN<11>
C687  Q_CAP_DIFFBUS  DIFF BUS_0.22UF 6.3V 20% X6S  pkg C0201  page 67 : 1 = P5E_CPU1_G1_TX_C_DP<11> ; 2 = P5E_CPU1_G1_TX_DP<11>
